(kicad_pcb
	(version 20260206)
	(generator "pcbnew")
	(generator_version "10.0")
	(general
		(thickness 1.6)
		(legacy_teardrops no)
	)
	(paper "A4")
	(title_block
		(title "04192023_DAF0TMB3IC0_F0TG_MB_C_brd_V02_OCP.brd")
		(comment 1 "Grand Teton / footprints 6830-6835 of 8354")
	)
	(layers
		(0 "F.Cu" signal "TOP")
		(4 "In1.Cu" signal "GND")
		(6 "In2.Cu" signal "IN1")
		(8 "In3.Cu" signal "GND1")
		(10 "In4.Cu" signal "IN2")
		(12 "In5.Cu" signal "GND2")
		(14 "In6.Cu" signal "IN3")
		(16 "In7.Cu" signal "GND3")
		(18 "In8.Cu" signal "VCC")
		(20 "In9.Cu" signal "VCC1")
		(22 "In10.Cu" signal "GND4")
		(24 "In11.Cu" signal "IN4")
		(26 "In12.Cu" signal "GND5")
		(28 "In13.Cu" signal "IN5")
		(30 "In14.Cu" signal "GND6")
		(32 "In15.Cu" signal "IN6")
		(34 "In16.Cu" signal "GND7")
		(2 "B.Cu" signal "BOTTOM")
		(9 "F.Adhes" user "F.Adhesive")
		(11 "B.Adhes" user "B.Adhesive")
		(13 "F.Paste" user "Package Geometry/Pastemask Top")
		(15 "B.Paste" user "Package Geometry/Pastemask Bottom")
		(5 "F.SilkS" user "Ref Des/Silkscreen Top")
		(7 "B.SilkS" user "Ref Des/Silkscreen Bottom")
		(1 "F.Mask" user "Board Geometry/Soldermask Top")
		(3 "B.Mask" user "Board Geometry/Soldermask Bottom")
		(17 "Dwgs.User" user "User.Drawings")
		(19 "Cmts.User" user "User.Comments")
		(21 "Eco1.User" user "User.Eco1")
		(23 "Eco2.User" user "User.Eco2")
		(25 "Edge.Cuts" user "Board Geometry/Outline")
		(27 "Margin" user)
		(31 "F.CrtYd" user "Package Geometry/Place Bound Top")
		(29 "B.CrtYd" user "Package Geometry/Place Bound Bottom")
		(35 "F.Fab" user "Ref Des/Assembly Top")
		(33 "B.Fab" user "Ref Des/Assembly Bottom")
	)
	(footprint ""
		(layer "B.Cu")
		(at 205.146148 -129.074164)
		(property "Reference" "R6807"
			(at 0 0 0)
			(layer "B.SilkS")
			(hide yes)
			(effects
				(font
					(size 1.27 1.27)
				)
				(justify mirror)
			)
		)
		(property "Value" ""
			(at 0 0 0)
			(layer "B.Fab")
			(effects
				(font
					(size 1.27 1.27)
				)
				(justify mirror)
			)
		)
		(duplicate_pad_numbers_are_jumpers no)
		(fp_line
			(start -0.7874 -0.4064)
			(end -0.7874 0.4064)
			(stroke
				(width 0.1524)
				(type default)
			)
			(layer "B.SilkS")
		)
		(fp_line
			(start -0.7874 0.4064)
			(end 0.7874 0.4064)
			(stroke
				(width 0.1524)
				(type default)
			)
			(layer "B.SilkS")
		)
		(fp_line
			(start 0.7874 -0.4064)
			(end -0.7874 -0.4064)
			(stroke
				(width 0.1524)
				(type default)
			)
			(layer "B.SilkS")
		)
		(fp_line
			(start 0.7874 0.4064)
			(end 0.7874 -0.4064)
			(stroke
				(width 0.1524)
				(type default)
			)
			(layer "B.SilkS")
		)
		(fp_line
			(start -0.67945 -0.3048)
			(end -0.67945 0.3048)
			(stroke
				(width 0.1)
				(type default)
			)
			(layer "B.Fab")
		)
		(fp_line
			(start -0.67945 0.3048)
			(end -0.120396 0.3048)
			(stroke
				(width 0.1)
				(type default)
			)
			(layer "B.Fab")
		)
		(fp_line
			(start -0.12065 -0.3048)
			(end -0.67945 -0.3048)
			(stroke
				(width 0.1)
				(type default)
			)
			(layer "B.Fab")
		)
		(fp_line
			(start -0.12065 -0.2794)
			(end -0.12065 -0.3048)
			(stroke
				(width 0.1)
				(type default)
			)
			(layer "B.Fab")
		)
		(fp_line
			(start -0.120396 0.2794)
			(end 0.12065 0.2794)
			(stroke
				(width 0.1)
				(type default)
			)
			(layer "B.Fab")
		)
		(fp_line
			(start -0.120396 0.3048)
			(end -0.120396 0.2794)
			(stroke
				(width 0.1)
				(type default)
			)
			(layer "B.Fab")
		)
		(fp_line
			(start 0.12065 -0.305054)
			(end 0.12065 -0.2794)
			(stroke
				(width 0.1)
				(type default)
			)
			(layer "B.Fab")
		)
		(fp_line
			(start 0.12065 -0.2794)
			(end -0.12065 -0.2794)
			(stroke
				(width 0.1)
				(type default)
			)
			(layer "B.Fab")
		)
		(fp_line
			(start 0.12065 0.2794)
			(end 0.12065 0.3048)
			(stroke
				(width 0.1)
				(type default)
			)
			(layer "B.Fab")
		)
		(fp_line
			(start 0.12065 0.3048)
			(end 0.67945 0.3048)
			(stroke
				(width 0.1)
				(type default)
			)
			(layer "B.Fab")
		)
		(fp_line
			(start 0.67945 -0.305054)
			(end 0.12065 -0.305054)
			(stroke
				(width 0.1)
				(type default)
			)
			(layer "B.Fab")
		)
		(fp_line
			(start 0.67945 0.3048)
			(end 0.67945 -0.305054)
			(stroke
				(width 0.1)
				(type default)
			)
			(layer "B.Fab")
		)
		(pad "1" smd circle
			(at 0.40005 0 180)
			(size 0 0)
			(layers "B.Cu" "B.Mask" "B.Paste")
			(net "RST_RT_CPU0_P1_RESET_R_N")
		)
		(pad "2" smd circle
			(at -0.40005 0 180)
			(size 0 0)
			(layers "B.Cu" "B.Mask" "B.Paste")
			(net "RST_RT_CPU0_P1_RESET_R2_N")
		)
	)
	(footprint ""
		(layer "B.Cu")
		(at 364.461806 -401.624546 180)
		(property "Reference" "R1095"
			(at 0 0 0)
			(layer "B.SilkS")
			(hide yes)
			(effects
				(font
					(size 1.27 1.27)
				)
				(justify mirror)
			)
		)
		(property "Value" ""
			(at 0 0 0)
			(layer "B.Fab")
			(effects
				(font
					(size 1.27 1.27)
				)
				(justify mirror)
			)
		)
		(duplicate_pad_numbers_are_jumpers no)
		(fp_line
			(start 1.2954 0.5842)
			(end 1.2954 -0.5842)
			(stroke
				(width 0.1524)
				(type default)
			)
			(layer "B.SilkS")
		)
		(fp_line
			(start 1.2954 -0.5842)
			(end -1.2954 -0.5842)
			(stroke
				(width 0.1524)
				(type default)
			)
			(layer "B.SilkS")
		)
		(fp_line
			(start -1.2954 0.5842)
			(end 1.2954 0.5842)
			(stroke
				(width 0.1524)
				(type default)
			)
			(layer "B.SilkS")
		)
		(fp_line
			(start -1.2954 -0.5842)
			(end -1.2954 0.5842)
			(stroke
				(width 0.1524)
				(type default)
			)
			(layer "B.SilkS")
		)
		(fp_line
			(start 1.1938 0.4064)
			(end 1.1938 -0.406654)
			(stroke
				(width 0.1)
				(type default)
			)
			(layer "B.Fab")
		)
		(fp_line
			(start 1.1938 -0.406654)
			(end 0.8636 -0.406654)
			(stroke
				(width 0.1)
				(type default)
			)
			(layer "B.Fab")
		)
		(fp_line
			(start 0.8636 0.4572)
			(end 0.8636 0.4318)
			(stroke
				(width 0.1)
				(type default)
			)
			(layer "B.Fab")
		)
		(fp_line
			(start 0.8636 0.4318)
			(end 0.8636 0.4064)
			(stroke
				(width 0.1)
				(type default)
			)
			(layer "B.Fab")
		)
		(fp_line
			(start 0.8636 0.4064)
			(end 1.1938 0.4064)
			(stroke
				(width 0.1)
				(type default)
			)
			(layer "B.Fab")
		)
		(fp_line
			(start 0.8636 -0.406654)
			(end 0.8636 -0.4572)
			(stroke
				(width 0.1)
				(type default)
			)
			(layer "B.Fab")
		)
		(fp_line
			(start 0.8636 -0.4572)
			(end -0.8636 -0.4572)
			(stroke
				(width 0.1)
				(type default)
			)
			(layer "B.Fab")
		)
		(fp_line
			(start -0.8636 0.4572)
			(end 0.8636 0.4572)
			(stroke
				(width 0.1)
				(type default)
			)
			(layer "B.Fab")
		)
		(fp_line
			(start -0.8636 0.4064)
			(end -0.8636 0.4572)
			(stroke
				(width 0.1)
				(type default)
			)
			(layer "B.Fab")
		)
		(fp_line
			(start -0.8636 -0.406654)
			(end -1.1938 -0.406654)
			(stroke
				(width 0.1)
				(type default)
			)
			(layer "B.Fab")
		)
		(fp_line
			(start -0.8636 -0.4572)
			(end -0.8636 -0.406654)
			(stroke
				(width 0.1)
				(type default)
			)
			(layer "B.Fab")
		)
		(fp_line
			(start -1.1938 0.4064)
			(end -0.8636 0.4064)
			(stroke
				(width 0.1)
				(type default)
			)
			(layer "B.Fab")
		)
		(fp_line
			(start -1.1938 -0.406654)
			(end -1.1938 0.4064)
			(stroke
				(width 0.1)
				(type default)
			)
			(layer "B.Fab")
		)
		(pad "1" smd rect
			(at 0.7366 0 90)
			(size 0.7112 0.8128)
			(layers "B.Cu" "B.Mask" "B.Paste")
			(net "P0V9_CPU0_RT3_2A_2D")
		)
		(pad "2" smd rect
			(at -0.7366 0 90)
			(size 0.7112 0.8128)
			(layers "B.Cu" "B.Mask" "B.Paste")
			(net "P0V9_CPU0_RT3_2A")
		)
	)
	(footprint ""
		(layer "B.Cu")
		(at 228.473508 -325.425562 180)
		(property "Reference" "C1087"
			(at 0 0 0)
			(layer "B.SilkS")
			(hide yes)
			(effects
				(font
					(size 1.27 1.27)
				)
				(justify mirror)
			)
		)
		(property "Value" ""
			(at 0 0 0)
			(layer "B.Fab")
			(effects
				(font
					(size 1.27 1.27)
				)
				(justify mirror)
			)
		)
		(duplicate_pad_numbers_are_jumpers no)
		(fp_line
			(start 0.7874 0.4064)
			(end 0.7874 -0.4064)
			(stroke
				(width 0.1524)
				(type default)
			)
			(layer "B.SilkS")
		)
		(fp_line
			(start 0.7874 -0.4064)
			(end -0.7874 -0.4064)
			(stroke
				(width 0.1524)
				(type default)
			)
			(layer "B.SilkS")
		)
		(fp_line
			(start -0.7874 0.4064)
			(end 0.7874 0.4064)
			(stroke
				(width 0.1524)
				(type default)
			)
			(layer "B.SilkS")
		)
		(fp_line
			(start -0.7874 -0.4064)
			(end -0.7874 0.4064)
			(stroke
				(width 0.1524)
				(type default)
			)
			(layer "B.SilkS")
		)
		(fp_line
			(start 0.67945 0.3048)
			(end 0.67945 -0.305054)
			(stroke
				(width 0.1)
				(type default)
			)
			(layer "B.Fab")
		)
		(fp_line
			(start 0.67945 -0.305054)
			(end 0.12065 -0.305054)
			(stroke
				(width 0.1)
				(type default)
			)
			(layer "B.Fab")
		)
		(fp_line
			(start 0.12065 0.3048)
			(end 0.67945 0.3048)
			(stroke
				(width 0.1)
				(type default)
			)
			(layer "B.Fab")
		)
		(fp_line
			(start 0.12065 0.2794)
			(end 0.12065 0.3048)
			(stroke
				(width 0.1)
				(type default)
			)
			(layer "B.Fab")
		)
		(fp_line
			(start 0.12065 -0.2794)
			(end -0.12065 -0.2794)
			(stroke
				(width 0.1)
				(type default)
			)
			(layer "B.Fab")
		)
		(fp_line
			(start 0.12065 -0.305054)
			(end 0.12065 -0.2794)
			(stroke
				(width 0.1)
				(type default)
			)
			(layer "B.Fab")
		)
		(fp_line
			(start -0.120396 0.3048)
			(end -0.120396 0.2794)
			(stroke
				(width 0.1)
				(type default)
			)
			(layer "B.Fab")
		)
		(fp_line
			(start -0.120396 0.2794)
			(end 0.12065 0.2794)
			(stroke
				(width 0.1)
				(type default)
			)
			(layer "B.Fab")
		)
		(fp_line
			(start -0.12065 -0.2794)
			(end -0.12065 -0.3048)
			(stroke
				(width 0.1)
				(type default)
			)
			(layer "B.Fab")
		)
		(fp_line
			(start -0.12065 -0.3048)
			(end -0.67945 -0.3048)
			(stroke
				(width 0.1)
				(type default)
			)
			(layer "B.Fab")
		)
		(fp_line
			(start -0.67945 0.3048)
			(end -0.120396 0.3048)
			(stroke
				(width 0.1)
				(type default)
			)
			(layer "B.Fab")
		)
		(fp_line
			(start -0.67945 -0.3048)
			(end -0.67945 0.3048)
			(stroke
				(width 0.1)
				(type default)
			)
			(layer "B.Fab")
		)
		(pad "1" smd circle
			(at 0.40005 0)
			(size 0 0)
			(layers "B.Cu" "B.Mask" "B.Paste")
			(net "P1V8_CPU0_RT_1D_ADC_TIC")
		)
		(pad "2" smd circle
			(at -0.40005 0)
			(size 0 0)
			(layers "B.Cu" "B.Mask" "B.Paste")
			(net "GND")
		)
	)
	(footprint ""
		(layer "B.Cu")
		(at 249.904504 -325.613522)
		(property "Reference" "U50"
			(at 1.648968 -3.641852 0)
			(unlocked yes)
			(layer "B.SilkS")
			(effects
				(font
					(size 0.7874 0.5842)
					(thickness 0.1524)
				)
				(justify left mirror)
			)
		)
		(property "Value" ""
			(at 0 0 0)
			(layer "B.Fab")
			(effects
				(font
					(size 1.27 1.27)
				)
				(justify mirror)
			)
		)
		(duplicate_pad_numbers_are_jumpers no)
		(fp_line
			(start -1.715516 -2.489962)
			(end -1.092962 -2.489962)
			(stroke
				(width 0.1524)
				(type default)
			)
			(layer "B.SilkS")
		)
		(fp_line
			(start -1.715516 2.489962)
			(end -1.715516 -2.489962)
			(stroke
				(width 0.1524)
				(type default)
			)
			(layer "B.SilkS")
		)
		(fp_line
			(start -1.092962 -2.489962)
			(end 0 -1.397)
			(stroke
				(width 0.1524)
				(type default)
			)
			(layer "B.SilkS")
		)
		(fp_line
			(start 0 -1.397)
			(end 1.092962 -2.489962)
			(stroke
				(width 0.1524)
				(type default)
			)
			(layer "B.SilkS")
		)
		(fp_line
			(start 1.092962 -2.489962)
			(end 1.715516 -2.489962)
			(stroke
				(width 0.1524)
				(type default)
			)
			(layer "B.SilkS")
		)
		(fp_line
			(start 1.715516 -2.489962)
			(end 1.715516 2.489962)
			(stroke
				(width 0.1524)
				(type default)
			)
			(layer "B.SilkS")
		)
		(fp_line
			(start 1.715516 2.489962)
			(end -1.715516 2.489962)
			(stroke
				(width 0.1524)
				(type default)
			)
			(layer "B.SilkS")
		)
		(fp_poly
			(pts
				(xy 5.225796 -2.72161) (xy 5.225796 -1.70561) (xy 4.209796 -2.21361)
			)
			(stroke
				(width 0)
				(type default)
			)
			(fill yes)
			(layer "B.SilkS")
		)
		(fp_line
			(start -1.994916 -2.489962)
			(end 1.994916 -2.489962)
			(stroke
				(width 0.1)
				(type default)
			)
			(layer "B.Fab")
		)
		(fp_line
			(start -1.994916 2.489962)
			(end -1.994916 -2.489962)
			(stroke
				(width 0.1)
				(type default)
			)
			(layer "B.Fab")
		)
		(fp_line
			(start 1.994916 -2.489962)
			(end 1.994916 2.489962)
			(stroke
				(width 0.1)
				(type default)
			)
			(layer "B.Fab")
		)
		(fp_line
			(start 1.994916 2.489962)
			(end -1.994916 2.489962)
			(stroke
				(width 0.1)
				(type default)
			)
			(layer "B.Fab")
		)
		(fp_poly
			(pts
				(xy 4.699 -2.7305) (xy 4.699 -1.7145) (xy 3.683 -2.2225)
			)
			(stroke
				(width 0)
				(type default)
			)
			(fill yes)
			(layer "B.Fab")
		)
		(pad "1" smd rect
			(at 2.655062 -2.2225 90)
			(size 0.381 1.6002)
			(layers "B.Cu" "B.Mask" "B.Paste")
			(net "MAX11617_2_VREF_R")
		)
		(pad "2" smd rect
			(at 2.655062 -1.5875 90)
			(size 0.381 1.6002)
			(layers "B.Cu" "B.Mask" "B.Paste")
			(net "GND")
		)
		(pad "3" smd rect
			(at 2.655062 -0.9525 90)
			(size 0.381 1.6002)
			(layers "B.Cu" "B.Mask" "B.Paste")
			(net "GND")
		)
		(pad "4" smd rect
			(at 2.655062 -0.3175 90)
			(size 0.381 1.6002)
			(layers "B.Cu" "B.Mask" "B.Paste")
			(net "GND")
		)
		(pad "5" smd rect
			(at 2.655062 0.3175 90)
			(size 0.381 1.6002)
			(layers "B.Cu" "B.Mask" "B.Paste")
			(net "P5V_AUX_ADC_MAM")
		)
		(pad "6" smd rect
			(at 2.655062 0.9525 90)
			(size 0.381 1.6002)
			(layers "B.Cu" "B.Mask" "B.Paste")
			(net "P1V8_AUX_ADC_MAM")
		)
		(pad "7" smd rect
			(at 2.655062 1.5875 90)
			(size 0.381 1.6002)
			(layers "B.Cu" "B.Mask" "B.Paste")
			(net "P1V2_AUX_ADC_MAM")
		)
		(pad "8" smd rect
			(at 2.655062 2.2225 90)
			(size 0.381 1.6002)
			(layers "B.Cu" "B.Mask" "B.Paste")
			(net "P1V8_CPU0_RT_1D_ADC_MAM")
		)
		(pad "9" smd rect
			(at -2.655062 2.2225 90)
			(size 0.381 1.6002)
			(layers "B.Cu" "B.Mask" "B.Paste")
			(net "P1V8_CPU1_RT_1D_ADC_MAM")
		)
		(pad "10" smd rect
			(at -2.655062 1.5875 90)
			(size 0.381 1.6002)
			(layers "B.Cu" "B.Mask" "B.Paste")
			(net "PVDD_33_S5_ADC_MAM")
		)
		(pad "11" smd rect
			(at -2.655062 0.9525 90)
			(size 0.381 1.6002)
			(layers "B.Cu" "B.Mask" "B.Paste")
			(net "PVDD18_S5_P0_ADC_MAM")
		)
		(pad "12" smd rect
			(at -2.655062 0.3175 90)
			(size 0.381 1.6002)
			(layers "B.Cu" "B.Mask" "B.Paste")
			(net "PVDD18_S5_P1_ADC_MAM")
		)
		(pad "13" smd rect
			(at -2.655062 -0.3175 90)
			(size 0.381 1.6002)
			(layers "B.Cu" "B.Mask" "B.Paste")
			(net "SMB_SEN_MAM_2_3V3AUX_SCL")
		)
		(pad "14" smd rect
			(at -2.655062 -0.9525 90)
			(size 0.381 1.6002)
			(layers "B.Cu" "B.Mask" "B.Paste")
			(net "SMB_SEN_MAM_2_3V3AUX_SDA")
		)
		(pad "15" smd rect
			(at -2.655062 -1.5875 90)
			(size 0.381 1.6002)
			(layers "B.Cu" "B.Mask" "B.Paste")
			(net "GND")
		)
		(pad "16" smd rect
			(at -2.655062 -2.2225 90)
			(size 0.381 1.6002)
			(layers "B.Cu" "B.Mask" "B.Paste")
			(net "P3V3_MAX11617_2_VDD")
		)
	)
	(footprint ""
		(layer "B.Cu")
		(at 109.550454 -32.587438 180)
		(property "Reference" "C6092"
			(at 0 0 0)
			(layer "B.SilkS")
			(hide yes)
			(effects
				(font
					(size 1.27 1.27)
				)
				(justify mirror)
			)
		)
		(property "Value" ""
			(at 0 0 0)
			(layer "B.Fab")
			(effects
				(font
					(size 1.27 1.27)
				)
				(justify mirror)
			)
		)
		(duplicate_pad_numbers_are_jumpers no)
		(fp_line
			(start 0.7874 0.4064)
			(end 0.7874 -0.4064)
			(stroke
				(width 0.1524)
				(type default)
			)
			(layer "B.SilkS")
		)
		(fp_line
			(start 0.7874 -0.4064)
			(end -0.7874 -0.4064)
			(stroke
				(width 0.1524)
				(type default)
			)
			(layer "B.SilkS")
		)
		(fp_line
			(start -0.7874 0.4064)
			(end 0.7874 0.4064)
			(stroke
				(width 0.1524)
				(type default)
			)
			(layer "B.SilkS")
		)
		(fp_line
			(start -0.7874 -0.4064)
			(end -0.7874 0.4064)
			(stroke
				(width 0.1524)
				(type default)
			)
			(layer "B.SilkS")
		)
		(fp_line
			(start 0.67945 0.3048)
			(end 0.67945 -0.305054)
			(stroke
				(width 0.1)
				(type default)
			)
			(layer "B.Fab")
		)
		(fp_line
			(start 0.67945 -0.305054)
			(end 0.12065 -0.305054)
			(stroke
				(width 0.1)
				(type default)
			)
			(layer "B.Fab")
		)
		(fp_line
			(start 0.12065 0.3048)
			(end 0.67945 0.3048)
			(stroke
				(width 0.1)
				(type default)
			)
			(layer "B.Fab")
		)
		(fp_line
			(start 0.12065 0.2794)
			(end 0.12065 0.3048)
			(stroke
				(width 0.1)
				(type default)
			)
			(layer "B.Fab")
		)
		(fp_line
			(start 0.12065 -0.2794)
			(end -0.12065 -0.2794)
			(stroke
				(width 0.1)
				(type default)
			)
			(layer "B.Fab")
		)
		(fp_line
			(start 0.12065 -0.305054)
			(end 0.12065 -0.2794)
			(stroke
				(width 0.1)
				(type default)
			)
			(layer "B.Fab")
		)
		(fp_line
			(start -0.120396 0.3048)
			(end -0.120396 0.2794)
			(stroke
				(width 0.1)
				(type default)
			)
			(layer "B.Fab")
		)
		(fp_line
			(start -0.120396 0.2794)
			(end 0.12065 0.2794)
			(stroke
				(width 0.1)
				(type default)
			)
			(layer "B.Fab")
		)
		(fp_line
			(start -0.12065 -0.2794)
			(end -0.12065 -0.3048)
			(stroke
				(width 0.1)
				(type default)
			)
			(layer "B.Fab")
		)
		(fp_line
			(start -0.12065 -0.3048)
			(end -0.67945 -0.3048)
			(stroke
				(width 0.1)
				(type default)
			)
			(layer "B.Fab")
		)
		(fp_line
			(start -0.67945 0.3048)
			(end -0.120396 0.3048)
			(stroke
				(width 0.1)
				(type default)
			)
			(layer "B.Fab")
		)
		(fp_line
			(start -0.67945 -0.3048)
			(end -0.67945 0.3048)
			(stroke
				(width 0.1)
				(type default)
			)
			(layer "B.Fab")
		)
		(pad "1" smd circle
			(at 0.40005 0)
			(size 0 0)
			(layers "B.Cu" "B.Mask" "B.Paste")
			(net "P3V3_AUX_CPU0_USB2_AVDD33")
		)
		(pad "2" smd circle
			(at -0.40005 0)
			(size 0 0)
			(layers "B.Cu" "B.Mask" "B.Paste")
			(net "GND")
		)
	)
	(footprint ""
		(layer "B.Cu")
		(at 320.616326 -416.899344 90)
		(property "Reference" "C6544"
			(at 0 0 90)
			(layer "B.SilkS")
			(hide yes)
			(effects
				(font
					(size 1.27 1.27)
				)
				(justify mirror)
			)
		)
		(property "Value" ""
			(at 0 0 90)
			(layer "B.Fab")
			(effects
				(font
					(size 1.27 1.27)
				)
				(justify mirror)
			)
		)
		(duplicate_pad_numbers_are_jumpers no)
		(fp_line
			(start 0.299974 -0.150114)
			(end -0.299974 -0.150114)
			(stroke
				(width 0.1)
				(type default)
			)
			(layer "B.Fab")
		)
		(fp_line
			(start -0.299974 -0.150114)
			(end -0.299974 0.150114)
			(stroke
				(width 0.1)
				(type default)
			)
			(layer "B.Fab")
		)
		(fp_line
			(start 0.299974 0.150114)
			(end 0.299974 -0.150114)
			(stroke
				(width 0.1)
				(type default)
			)
			(layer "B.Fab")
		)
		(fp_line
			(start -0.299974 0.150114)
			(end 0.299974 0.150114)
			(stroke
				(width 0.1)
				(type default)
			)
			(layer "B.Fab")
		)
		(pad "1" smd rect
			(at 0.2667 0 270)
			(size 0.3048 0.381)
			(layers "B.Cu" "B.Mask" "B.Paste")
			(net "P5E_CPU0_P1_TX_BUF_C_DN<5>")
		)
		(pad "2" smd rect
			(at -0.2667 0 270)
			(size 0.3048 0.381)
			(layers "B.Cu" "B.Mask" "B.Paste")
			(net "P5E_CPU0_P1_TX_BUF_DN<5>")
		)
	)
)
